# T6G (Grand Teton) — schematic netlist excerpt (pin names and nets, part order shuffled) for the footprints in the layout excerpt that follows; sources: Cadence DE-HDL packaged netlist, KiCad conversion of 04192023_DAF0TMB3IC0_F0TG_MB_C_brd_V02_OCP.brd

PR424  Q_RES  5.6 1% CHIP  pkg 0402LF  page 213 : A = SW_PVDDCR_CPU0_P1_BOOT6 ; B = SW_PVDDCR_CPU0_P1_BOOT6_RC

Q95  MOSFET_NCH_DUAL  PJT138K IC  pkg SOT363XD  page 144
  S1  = GND
  G1  = HDD_ACTIVITY_BUF
  D2  = NC_Q95_D2
  S2  = NC_Q95_S2
  G2  = NC_Q95_G2
  D1  = HDD_ACTIVITY_BUF_N

TP15  TP  NA  pkg TP  page 54 : TP = VSENSE_PVDDIO_P1_DP

(kicad_pcb
	(version 20260206)
	(generator "pcbnew")
	(generator_version "10.0")
	(general
		(thickness 1.6)
		(legacy_teardrops no)
	)
	(paper "A4")
	(title_block
		(title "04192023_DAF0TMB3IC0_F0TG_MB_C_brd_V02_OCP.brd")
		(comment 1 "Grand Teton / footprints 1702-1704 of 8354")
	)
	(layers
		(0 "F.Cu" signal "TOP")
		(4 "In1.Cu" signal "GND")
		(6 "In2.Cu" signal "IN1")
		(8 "In3.Cu" signal "GND1")
		(10 "In4.Cu" signal "IN2")
		(12 "In5.Cu" signal "GND2")
		(14 "In6.Cu" signal "IN3")
		(16 "In7.Cu" signal "GND3")
		(18 "In8.Cu" signal "VCC")
		(20 "In9.Cu" signal "VCC1")
		(22 "In10.Cu" signal "GND4")
		(24 "In11.Cu" signal "IN4")
		(26 "In12.Cu" signal "GND5")
		(28 "In13.Cu" signal "IN5")
		(30 "In14.Cu" signal "GND6")
		(32 "In15.Cu" signal "IN6")
		(34 "In16.Cu" signal "GND7")
		(2 "B.Cu" signal "BOTTOM")
		(9 "F.Adhes" user "F.Adhesive")
		(11 "B.Adhes" user "B.Adhesive")
		(13 "F.Paste" user "Package Geometry/Pastemask Top")
		(15 "B.Paste" user "Package Geometry/Pastemask Bottom")
		(5 "F.SilkS" user "Ref Des/Silkscreen Top")
		(7 "B.SilkS" user "Ref Des/Silkscreen Bottom")
		(1 "F.Mask" user "Board Geometry/Soldermask Top")
		(3 "B.Mask" user "Board Geometry/Soldermask Bottom")
		(17 "Dwgs.User" user "User.Drawings")
		(19 "Cmts.User" user "User.Comments")
		(21 "Eco1.User" user "User.Eco1")
		(23 "Eco2.User" user "User.Eco2")
		(25 "Edge.Cuts" user "Board Geometry/Outline")
		(27 "Margin" user)
		(31 "F.CrtYd" user "Package Geometry/Place Bound Top")
		(29 "B.CrtYd" user "Package Geometry/Place Bound Bottom")
		(35 "F.Fab" user "Ref Des/Assembly Top")
		(33 "B.Fab" user "Ref Des/Assembly Bottom")
	)
	(footprint ""
		(layer "F.Cu")
		(at 144.690592 -104.974898)
		(property "Reference" "Q95"
			(at -3.91668 -1.633728 0)
			(unlocked yes)
			(layer "F.SilkS")
			(effects
				(font
					(size 0.7874 0.5842)
					(thickness 0.1524)
				)
				(justify left)
			)
		)
		(property "Value" ""
			(at 0 0 0)
			(layer "F.Fab")
			(effects
				(font
					(size 1.27 1.27)
				)
			)
		)
		(duplicate_pad_numbers_are_jumpers no)
		(fp_line
			(start -1.332738 -1.100074)
			(end -0.4826 -1.100074)
			(stroke
				(width 0.1524)
				(type default)
			)
			(layer "F.SilkS")
		)
		(fp_line
			(start -1.332738 1.100074)
			(end -1.332738 -1.100074)
			(stroke
				(width 0.1524)
				(type default)
			)
			(layer "F.SilkS")
		)
		(fp_line
			(start -0.4826 -1.100074)
			(end 0 -0.541274)
			(stroke
				(width 0.1524)
				(type default)
			)
			(layer "F.SilkS")
		)
		(fp_line
			(start 0 -0.541274)
			(end 0.4826 -1.100074)
			(stroke
				(width 0.1524)
				(type default)
			)
			(layer "F.SilkS")
		)
		(fp_line
			(start 0.4826 -1.100074)
			(end 1.332738 -1.100074)
			(stroke
				(width 0.1524)
				(type default)
			)
			(layer "F.SilkS")
		)
		(fp_line
			(start 1.332738 -1.100074)
			(end 1.332738 1.100074)
			(stroke
				(width 0.1524)
				(type default)
			)
			(layer "F.SilkS")
		)
		(fp_line
			(start 1.332738 1.100074)
			(end -1.332738 1.100074)
			(stroke
				(width 0.1524)
				(type default)
			)
			(layer "F.SilkS")
		)
		(fp_poly
			(pts
				(xy -1.533144 -0.649986) (xy -2.1082 -0.362458) (xy -2.1082 -0.937514)
			)
			(stroke
				(width 0)
				(type default)
			)
			(fill yes)
			(layer "F.SilkS")
		)
		(fp_line
			(start -0.674878 -1.100074)
			(end 0.674878 -1.100074)
			(stroke
				(width 0.1)
				(type default)
			)
			(layer "F.Fab")
		)
		(fp_line
			(start -0.674878 1.100074)
			(end -0.674878 -1.100074)
			(stroke
				(width 0.1)
				(type default)
			)
			(layer "F.Fab")
		)
		(fp_line
			(start 0.674878 -1.100074)
			(end 0.674878 1.100074)
			(stroke
				(width 0.1)
				(type default)
			)
			(layer "F.Fab")
		)
		(fp_line
			(start 0.674878 1.100074)
			(end -0.674878 1.100074)
			(stroke
				(width 0.1)
				(type default)
			)
			(layer "F.Fab")
		)
		(fp_poly
			(pts
				(xy -2.2352 -0.298958) (xy -2.2352 -1.001014) (xy -1.533144 -0.649986)
			)
			(stroke
				(width 0)
				(type default)
			)
			(fill yes)
			(layer "F.Fab")
		)
		(pad "1" smd rect
			(at -0.94996 -0.649986 90)
			(size 0.4318 0.508)
			(layers "F.Cu" "F.Mask" "F.Paste")
			(net "GND")
		)
		(pad "2" smd rect
			(at -0.94996 0 90)
			(size 0.4318 0.508)
			(layers "F.Cu" "F.Mask" "F.Paste")
			(net "HDD_ACTIVITY_BUF")
		)
		(pad "3" smd rect
			(at -0.94996 0.649986 90)
			(size 0.4318 0.508)
			(layers "F.Cu" "F.Mask" "F.Paste")
			(net "NC_Q95_D2")
		)
		(pad "4" smd rect
			(at 0.94996 0.649986 90)
			(size 0.4318 0.508)
			(layers "F.Cu" "F.Mask" "F.Paste")
			(net "NC_Q95_S2")
		)
		(pad "5" smd rect
			(at 0.94996 0 90)
			(size 0.4318 0.508)
			(layers "F.Cu" "F.Mask" "F.Paste")
			(net "NC_Q95_G2")
		)
		(pad "6" smd rect
			(at 0.94996 -0.649986 90)
			(size 0.4318 0.508)
			(layers "F.Cu" "F.Mask" "F.Paste")
			(net "HDD_ACTIVITY_BUF_N")
		)
	)
	(footprint ""
		(layer "F.Cu")
		(at 64.888364 -164.276786 -90)
		(property "Reference" "PR424"
			(at 0 0 270)
			(layer "F.SilkS")
			(hide yes)
			(effects
				(font
					(size 1.27 1.27)
				)
			)
		)
		(property "Value" ""
			(at 0 0 270)
			(layer "F.Fab")
			(effects
				(font
					(size 1.27 1.27)
				)
			)
		)
		(duplicate_pad_numbers_are_jumpers no)
		(fp_line
			(start -0.7874 0.4064)
			(end -0.7874 -0.4064)
			(stroke
				(width 0.1524)
				(type default)
			)
			(layer "F.SilkS")
		)
		(fp_line
			(start 0.7874 0.4064)
			(end -0.7874 0.4064)
			(stroke
				(width 0.1524)
				(type default)
			)
			(layer "F.SilkS")
		)
		(fp_line
			(start -0.7874 -0.4064)
			(end 0.7874 -0.4064)
			(stroke
				(width 0.1524)
				(type default)
			)
			(layer "F.SilkS")
		)
		(fp_line
			(start 0.7874 -0.4064)
			(end 0.7874 0.4064)
			(stroke
				(width 0.1524)
				(type default)
			)
			(layer "F.SilkS")
		)
		(fp_line
			(start -0.67945 0.3048)
			(end -0.67945 -0.305054)
			(stroke
				(width 0.1)
				(type default)
			)
			(layer "F.Fab")
		)
		(fp_line
			(start -0.12065 0.3048)
			(end -0.67945 0.3048)
			(stroke
				(width 0.1)
				(type default)
			)
			(layer "F.Fab")
		)
		(fp_line
			(start 0.120396 0.3048)
			(end 0.120396 0.2794)
			(stroke
				(width 0.1)
				(type default)
			)
			(layer "F.Fab")
		)
		(fp_line
			(start 0.67945 0.3048)
			(end 0.120396 0.3048)
			(stroke
				(width 0.1)
				(type default)
			)
			(layer "F.Fab")
		)
		(fp_line
			(start -0.12065 0.2794)
			(end -0.12065 0.3048)
			(stroke
				(width 0.1)
				(type default)
			)
			(layer "F.Fab")
		)
		(fp_line
			(start 0.120396 0.2794)
			(end -0.12065 0.2794)
			(stroke
				(width 0.1)
				(type default)
			)
			(layer "F.Fab")
		)
		(fp_line
			(start -0.12065 -0.2794)
			(end 0.12065 -0.2794)
			(stroke
				(width 0.1)
				(type default)
			)
			(layer "F.Fab")
		)
		(fp_line
			(start 0.12065 -0.2794)
			(end 0.12065 -0.3048)
			(stroke
				(width 0.1)
				(type default)
			)
			(layer "F.Fab")
		)
		(fp_line
			(start 0.12065 -0.3048)
			(end 0.67945 -0.3048)
			(stroke
				(width 0.1)
				(type default)
			)
			(layer "F.Fab")
		)
		(fp_line
			(start 0.67945 -0.3048)
			(end 0.67945 0.3048)
			(stroke
				(width 0.1)
				(type default)
			)
			(layer "F.Fab")
		)
		(fp_line
			(start -0.67945 -0.305054)
			(end -0.12065 -0.305054)
			(stroke
				(width 0.1)
				(type default)
			)
			(layer "F.Fab")
		)
		(fp_line
			(start -0.12065 -0.305054)
			(end -0.12065 -0.2794)
			(stroke
				(width 0.1)
				(type default)
			)
			(layer "F.Fab")
		)
		(pad "1" smd circle
			(at -0.40005 0 270)
			(size 0 0)
			(layers "F.Cu" "F.Mask" "F.Paste")
			(net "SW_PVDDCR_CPU0_P1_BOOT6")
		)
		(pad "2" smd circle
			(at 0.40005 0 270)
			(size 0 0)
			(layers "F.Cu" "F.Mask" "F.Paste")
			(net "SW_PVDDCR_CPU0_P1_BOOT6_RC")
		)
	)
	(footprint ""
		(layer "F.Cu")
		(at 20.00504 -332.004924 180)
		(property "Reference" "TP15"
			(at 6.88848 1.024382 0)
			(unlocked yes)
			(layer "F.SilkS")
			(effects
				(font
					(size 0.7874 0.5842)
					(thickness 0.1524)
				)
				(justify left)
			)
		)
		(property "Value" ""
			(at 0 0 180)
			(layer "F.Fab")
			(effects
				(font
					(size 1.27 1.27)
				)
			)
		)
		(duplicate_pad_numbers_are_jumpers no)
		(pad "1" smd circle
			(at 0 0 180)
			(size 0.762 0.762)
			(layers "F.Cu" "F.Mask" "F.Paste")
			(net "VSENSE_PVDDIO_P1_DP")
		)
	)
)
